# BASEBOARD_FAB2 (Tioga Pass) — schematic netlist excerpt (pin names and nets, part order shuffled) for the footprints in the layout excerpt that follows; sources: Cadence DE-HDL packaged netlist, KiCad conversion of Wiwynn_Tioga_Pass_MB.brd

C1B10  CAPP  270UF 16V 20% OSCON  pkg 2626  page 228 : A = VR_FET_SW_P12V_STBY_PVDDQ_KLM ; B = GND
L1G1  IND-120NH-30-GP  pkg DISCRET-GB2  page 224 : S = VR_PVDDQ_GHJ_PH1_SW ; F = PVDDQ_GHJ

(kicad_pcb
	(version 20260206)
	(generator "pcbnew")
	(generator_version "10.0")
	(general
		(thickness 1.6)
		(legacy_teardrops no)
	)
	(paper "A4")
	(title_block
		(title "Wiwynn_Tioga_Pass_MB.brd")
		(comment 1 "Tioga Pass / footprints 1095-1096 of 4770")
	)
	(layers
		(0 "F.Cu" signal "TOP")
		(4 "In1.Cu" signal "L2GND")
		(6 "In2.Cu" signal "L3")
		(8 "In3.Cu" signal "L4GND")
		(10 "In4.Cu" signal "L5")
		(12 "In5.Cu" signal "L6GND")
		(14 "In6.Cu" signal "L7VCC")
		(16 "In7.Cu" signal "L8VCC")
		(18 "In8.Cu" signal "L9GND")
		(20 "In9.Cu" signal "L10")
		(22 "In10.Cu" signal "L11GND")
		(24 "In11.Cu" signal "L12")
		(26 "In12.Cu" signal "L13GND")
		(2 "B.Cu" signal "BOTTOM")
		(9 "F.Adhes" user "F.Adhesive")
		(11 "B.Adhes" user "B.Adhesive")
		(13 "F.Paste" user "Package Geometry/Pastemask Top")
		(15 "B.Paste" user "Package Geometry/Pastemask Bottom")
		(5 "F.SilkS" user "Ref Des/Silkscreen Top")
		(7 "B.SilkS" user "Ref Des/Silkscreen Bottom")
		(1 "F.Mask" user "Board Geometry/Soldermask Top")
		(3 "B.Mask" user "Board Geometry/Soldermask Bottom")
		(17 "Dwgs.User" user "User.Drawings")
		(19 "Cmts.User" user "User.Comments")
		(21 "Eco1.User" user "User.Eco1")
		(23 "Eco2.User" user "User.Eco2")
		(25 "Edge.Cuts" user "Board Geometry/Outline")
		(27 "Margin" user)
		(31 "F.CrtYd" user "Package Geometry/Place Bound Top")
		(29 "B.CrtYd" user "Package Geometry/Place Bound Bottom")
		(35 "F.Fab" user "Ref Des/Assembly Top")
		(33 "B.Fab" user "Ref Des/Assembly Bottom")
	)
	(footprint ""
		(layer "F.Cu")
		(at 10.8204 -8.951976)
		(property "Reference" "L1G1"
			(at 3.378708 -4.251706 0)
			(unlocked yes)
			(layer "F.SilkS")
			(effects
				(font
					(size 0.4064 0.254)
					(thickness 0.1524)
				)
			)
		)
		(property "Value" ""
			(at 0 0 0)
			(layer "F.Fab")
			(effects
				(font
					(size 1.27 1.27)
				)
			)
		)
		(duplicate_pad_numbers_are_jumpers no)
		(fp_line
			(start -1.1303 -3.199892)
			(end 8.3693 -3.199892)
			(stroke
				(width 0.1524)
				(type default)
			)
			(layer "F.SilkS")
		)
		(fp_line
			(start -1.1303 -1.6637)
			(end -1.1303 -3.199892)
			(stroke
				(width 0.1524)
				(type default)
			)
			(layer "F.SilkS")
		)
		(fp_line
			(start -1.1303 3.199892)
			(end -1.1303 1.6637)
			(stroke
				(width 0.1524)
				(type default)
			)
			(layer "F.SilkS")
		)
		(fp_line
			(start 8.3693 -3.199892)
			(end 8.3693 -1.6637)
			(stroke
				(width 0.1524)
				(type default)
			)
			(layer "F.SilkS")
		)
		(fp_line
			(start 8.3693 1.6637)
			(end 8.3693 3.199892)
			(stroke
				(width 0.1524)
				(type default)
			)
			(layer "F.SilkS")
		)
		(fp_line
			(start 8.3693 3.199892)
			(end -1.1303 3.199892)
			(stroke
				(width 0.1524)
				(type default)
			)
			(layer "F.SilkS")
		)
		(fp_rect
			(start -1.1303 3.199892)
			(end 8.3693 -3.199892)
			(stroke
				(width 0)
				(type default)
			)
			(fill no)
			(layer "F.CrtYd")
		)
		(fp_line
			(start -1.1303 -3.199892)
			(end 8.3693 -3.199892)
			(stroke
				(width 0.1)
				(type default)
			)
			(layer "F.Fab")
		)
		(fp_line
			(start -1.1303 3.199892)
			(end -1.1303 -3.199892)
			(stroke
				(width 0.1)
				(type default)
			)
			(layer "F.Fab")
		)
		(fp_line
			(start 8.3693 -3.199892)
			(end 8.3693 3.199892)
			(stroke
				(width 0.1)
				(type default)
			)
			(layer "F.Fab")
		)
		(fp_line
			(start 8.3693 3.199892)
			(end -1.1303 3.199892)
			(stroke
				(width 0.1)
				(type default)
			)
			(layer "F.Fab")
		)
		(pad "1" smd rect
			(at 0 0)
			(size 3.683 2.667)
			(layers "F.Cu" "F.Mask" "F.Paste")
			(net "VR_PVDDQ_GHJ_PH1_SW")
		)
		(pad "2" smd rect
			(at 7.239 0)
			(size 3.683 2.667)
			(layers "F.Cu" "F.Mask" "F.Paste")
			(net "PVDDQ_GHJ")
		)
	)
	(footprint ""
		(layer "F.Cu")
		(at 14.7066 -126.6825 90)
		(property "Reference" "C1B10"
			(at 5.68833 3.1496 0)
			(unlocked yes)
			(layer "F.SilkS")
			(effects
				(font
					(size 0.7874 0.5842)
					(thickness 0.1524)
				)
				(justify left)
			)
		)
		(property "Value" ""
			(at 0 0 90)
			(layer "F.Fab")
			(effects
				(font
					(size 1.27 1.27)
				)
			)
		)
		(duplicate_pad_numbers_are_jumpers no)
		(fp_line
			(start 0.9017 -1.714246)
			(end 0.7239 -1.714246)
			(stroke
				(width 0.1524)
				(type default)
			)
			(layer "F.SilkS")
		)
		(fp_line
			(start -0.7239 -1.714246)
			(end -0.9017 -1.714246)
			(stroke
				(width 0.1524)
				(type default)
			)
			(layer "F.SilkS")
		)
		(fp_line
			(start -0.9017 -1.714246)
			(end -0.9017 1.587754)
			(stroke
				(width 0.1524)
				(type default)
			)
			(layer "F.SilkS")
		)
		(fp_line
			(start 2.638044 -0.733044)
			(end 0.9017 -0.733044)
			(stroke
				(width 0.1524)
				(type default)
			)
			(layer "F.SilkS")
		)
		(fp_line
			(start -0.9017 -0.733044)
			(end -2.638044 -0.733044)
			(stroke
				(width 0.1524)
				(type default)
			)
			(layer "F.SilkS")
		)
		(fp_line
			(start -2.638044 -0.733044)
			(end -3.400044 0.028956)
			(stroke
				(width 0.1524)
				(type default)
			)
			(layer "F.SilkS")
		)
		(fp_line
			(start 3.400044 0.028956)
			(end 2.638044 -0.733044)
			(stroke
				(width 0.1524)
				(type default)
			)
			(layer "F.SilkS")
		)
		(fp_line
			(start -3.400044 0.028956)
			(end -3.400044 6.067044)
			(stroke
				(width 0.1524)
				(type default)
			)
			(layer "F.SilkS")
		)
		(fp_line
			(start 0.9017 1.587754)
			(end 0.9017 -1.714246)
			(stroke
				(width 0.1524)
				(type default)
			)
			(layer "F.SilkS")
		)
		(fp_line
			(start 0.7239 1.587754)
			(end 0.9017 1.587754)
			(stroke
				(width 0.1524)
				(type default)
			)
			(layer "F.SilkS")
		)
		(fp_line
			(start -0.9017 1.587754)
			(end -0.7239 1.587754)
			(stroke
				(width 0.1524)
				(type default)
			)
			(layer "F.SilkS")
		)
		(fp_line
			(start 3.400044 6.067044)
			(end 3.400044 0.028956)
			(stroke
				(width 0.1524)
				(type default)
			)
			(layer "F.SilkS")
		)
		(fp_line
			(start 0.9017 6.067044)
			(end 3.400044 6.067044)
			(stroke
				(width 0.1524)
				(type default)
			)
			(layer "F.SilkS")
		)
		(fp_line
			(start -3.400044 6.067044)
			(end -0.9017 6.067044)
			(stroke
				(width 0.1524)
				(type default)
			)
			(layer "F.SilkS")
		)
		(fp_poly
			(pts
				(xy -3.400044 6.067044) (xy 3.400044 6.067044) (xy 3.400044 0.028956) (xy 2.638044 -0.733044) (xy -2.638044 -0.733044)
				(xy -3.400044 0.028956)
			)
			(stroke
				(width 0)
				(type default)
			)
			(fill no)
			(layer "F.CrtYd")
		)
		(fp_line
			(start 2.638044 -0.733044)
			(end -2.638044 -0.733044)
			(stroke
				(width 0.1)
				(type default)
			)
			(layer "F.Fab")
		)
		(fp_line
			(start -2.638044 -0.733044)
			(end -3.400044 0.028956)
			(stroke
				(width 0.1)
				(type default)
			)
			(layer "F.Fab")
		)
		(fp_line
			(start 3.400044 0.028956)
			(end 2.638044 -0.733044)
			(stroke
				(width 0.1)
				(type default)
			)
			(layer "F.Fab")
		)
		(fp_line
			(start -3.400044 0.028956)
			(end -3.400044 6.067044)
			(stroke
				(width 0.1)
				(type default)
			)
			(layer "F.Fab")
		)
		(fp_line
			(start 3.400044 6.067044)
			(end 3.400044 0.028956)
			(stroke
				(width 0.1)
				(type default)
			)
			(layer "F.Fab")
		)
		(fp_line
			(start -3.400044 6.067044)
			(end 3.400044 6.067044)
			(stroke
				(width 0.1)
				(type default)
			)
			(layer "F.Fab")
		)
		(fp_circle
			(center 0 2.667)
			(end 0 6.067044)
			(stroke
				(width 0.1)
				(type default)
			)
			(fill no)
			(layer "F.Fab")
		)
		(pad "1" smd rect
			(at 0 0 90)
			(size 0.7874 3.429)
			(layers "F.Cu" "F.Mask" "F.Paste")
			(net "VR_FET_SW_P12V_STBY_PVDDQ_KLM")
		)
		(pad "2" smd rect
			(at 0 5.334 90)
			(size 0.7874 3.429)
			(layers "F.Cu" "F.Mask" "F.Paste")
			(net "GND")
		)
	)
)
